(kicad_pcb
	(version 20260206)
	(generator "pcbnew")
	(generator_version "10.0")
	(general
		(thickness 1.6)
		(legacy_teardrops no)
	)
	(paper "A4")
	(title_block
		(title "01162023_DA0F0TEBIF0_F0T_Expander_BD_F_brd_V02_OCP.brd")
		(comment 1 "Grand Teton / footprints 4450-4450 of 9728")
	)
	(layers
		(0 "F.Cu" signal "TOP")
		(4 "In1.Cu" signal "GND")
		(6 "In2.Cu" signal "VCC")
		(8 "In3.Cu" signal "VCC1")
		(10 "In4.Cu" signal "GND1")
		(12 "In5.Cu" signal "IN1")
		(14 "In6.Cu" signal "GND2")
		(16 "In7.Cu" signal "IN2")
		(18 "In8.Cu" signal "GND3")
		(20 "In9.Cu" signal "IN3")
		(22 "In10.Cu" signal "GND4")
		(24 "In11.Cu" signal "IN4")
		(26 "In12.Cu" signal "GND5")
		(28 "In13.Cu" signal "IN5")
		(30 "In14.Cu" signal "GND6")
		(32 "In15.Cu" signal "IN6")
		(34 "In16.Cu" signal "GND7")
		(2 "B.Cu" signal "BOTTOM")
		(9 "F.Adhes" user "F.Adhesive")
		(11 "B.Adhes" user "B.Adhesive")
		(13 "F.Paste" user "Package Geometry/Pastemask Top")
		(15 "B.Paste" user "Package Geometry/Pastemask Bottom")
		(5 "F.SilkS" user "Ref Des/Silkscreen Top")
		(7 "B.SilkS" user "Ref Des/Silkscreen Bottom")
		(1 "F.Mask" user "Board Geometry/Soldermask Top")
		(3 "B.Mask" user "Board Geometry/Soldermask Bottom")
		(17 "Dwgs.User" user "User.Drawings")
		(19 "Cmts.User" user "User.Comments")
		(21 "Eco1.User" user "User.Eco1")
		(23 "Eco2.User" user "User.Eco2")
		(25 "Edge.Cuts" user "Board Geometry/Outline")
		(27 "Margin" user)
		(31 "F.CrtYd" user "Package Geometry/Place Bound Top")
		(29 "B.CrtYd" user "Package Geometry/Place Bound Bottom")
		(35 "F.Fab" user "Ref Des/Assembly Top")
		(33 "B.Fab" user "Ref Des/Assembly Bottom")
	)
	(footprint ""
		(layer "F.Cu")
		(at 224.718118 -319.392554 180)
		(property "Reference" "PC223"
			(at 0 0 180)
			(layer "F.SilkS")
			(hide yes)
			(effects
				(font
					(size 1.27 1.27)
				)
			)
		)
		(property "Value" ""
			(at 0 0 180)
			(layer "F.Fab")
			(effects
				(font
					(size 1.27 1.27)
				)
			)
		)
		(duplicate_pad_numbers_are_jumpers no)
		(fp_line
			(start 0.7874 0.4064)
			(end -0.7874 0.4064)
			(stroke
				(width 0.1524)
				(type default)
			)
			(layer "F.SilkS")
		)
		(fp_line
			(start 0.7874 -0.4064)
			(end 0.7874 0.4064)
			(stroke
				(width 0.1524)
				(type default)
			)
			(layer "F.SilkS")
		)
		(fp_line
			(start -0.7874 0.4064)
			(end -0.7874 -0.4064)
			(stroke
				(width 0.1524)
				(type default)
			)
			(layer "F.SilkS")
		)
		(fp_line
			(start -0.7874 -0.4064)
			(end 0.7874 -0.4064)
			(stroke
				(width 0.1524)
				(type default)
			)
			(layer "F.SilkS")
		)
		(fp_line
			(start 0.67945 0.3048)
			(end 0.120396 0.3048)
			(stroke
				(width 0.1)
				(type default)
			)
			(layer "F.Fab")
		)
		(fp_line
			(start 0.67945 -0.3048)
			(end 0.67945 0.3048)
			(stroke
				(width 0.1)
				(type default)
			)
			(layer "F.Fab")
		)
		(fp_line
			(start 0.12065 -0.2794)
			(end 0.12065 -0.3048)
			(stroke
				(width 0.1)
				(type default)
			)
			(layer "F.Fab")
		)
		(fp_line
			(start 0.12065 -0.3048)
			(end 0.67945 -0.3048)
			(stroke
				(width 0.1)
				(type default)
			)
			(layer "F.Fab")
		)
		(fp_line
			(start 0.120396 0.3048)
			(end 0.120396 0.2794)
			(stroke
				(width 0.1)
				(type default)
			)
			(layer "F.Fab")
		)
		(fp_line
			(start 0.120396 0.2794)
			(end -0.12065 0.2794)
			(stroke
				(width 0.1)
				(type default)
			)
			(layer "F.Fab")
		)
		(fp_line
			(start -0.12065 0.3048)
			(end -0.67945 0.3048)
			(stroke
				(width 0.1)
				(type default)
			)
			(layer "F.Fab")
		)
		(fp_line
			(start -0.12065 0.2794)
			(end -0.12065 0.3048)
			(stroke
				(width 0.1)
				(type default)
			)
			(layer "F.Fab")
		)
		(fp_line
			(start -0.12065 -0.2794)
			(end 0.12065 -0.2794)
			(stroke
				(width 0.1)
				(type default)
			)
			(layer "F.Fab")
		)
		(fp_line
			(start -0.12065 -0.305054)
			(end -0.12065 -0.2794)
			(stroke
				(width 0.1)
				(type default)
			)
			(layer "F.Fab")
		)
		(fp_line
			(start -0.67945 0.3048)
			(end -0.67945 -0.305054)
			(stroke
				(width 0.1)
				(type default)
			)
			(layer "F.Fab")
		)
		(fp_line
			(start -0.67945 -0.305054)
			(end -0.12065 -0.305054)
			(stroke
				(width 0.1)
				(type default)
			)
			(layer "F.Fab")
		)
		(pad "1" smd circle
			(at -0.40005 0 180)
			(size 0 0)
			(layers "F.Cu" "F.Mask" "F.Paste")
			(net "P12V_AUX")
		)
		(pad "2" smd circle
			(at 0.40005 0 180)
			(size 0 0)
			(layers "F.Cu" "F.Mask" "F.Paste")
			(net "GND")
		)
	)
)
